(kicad_pcb
	(version 20260206)
	(generator "pcbnew")
	(generator_version "10.0")
	(general
		(thickness 1.6)
		(legacy_teardrops no)
	)
	(paper "A4")
	(title_block
		(title "03242023_DA0F0TMBIJ0_F0T_Motherboard_J_brd_V01_OCP.brd")
		(comment 1 "Grand Teton / footprints 3457-3462 of 6105")
	)
	(layers
		(0 "F.Cu" signal "TOP")
		(4 "In1.Cu" signal "GND")
		(6 "In2.Cu" signal "IN1")
		(8 "In3.Cu" signal "GND1")
		(10 "In4.Cu" signal "IN2")
		(12 "In5.Cu" signal "GND2")
		(14 "In6.Cu" signal "IN3")
		(16 "In7.Cu" signal "GND3")
		(18 "In8.Cu" signal "VCC")
		(20 "In9.Cu" signal "VCC1")
		(22 "In10.Cu" signal "GND4")
		(24 "In11.Cu" signal "IN4")
		(26 "In12.Cu" signal "GND5")
		(28 "In13.Cu" signal "IN5")
		(30 "In14.Cu" signal "GND6")
		(32 "In15.Cu" signal "IN6")
		(34 "In16.Cu" signal "GND7")
		(2 "B.Cu" signal "BOTTOM")
		(9 "F.Adhes" user "F.Adhesive")
		(11 "B.Adhes" user "B.Adhesive")
		(13 "F.Paste" user "Package Geometry/Pastemask Top")
		(15 "B.Paste" user "Package Geometry/Pastemask Bottom")
		(5 "F.SilkS" user "Ref Des/Silkscreen Top")
		(7 "B.SilkS" user "Ref Des/Silkscreen Bottom")
		(1 "F.Mask" user "Board Geometry/Soldermask Top")
		(3 "B.Mask" user "Board Geometry/Soldermask Bottom")
		(17 "Dwgs.User" user "User.Drawings")
		(19 "Cmts.User" user "User.Comments")
		(21 "Eco1.User" user "User.Eco1")
		(23 "Eco2.User" user "User.Eco2")
		(25 "Edge.Cuts" user "Board Geometry/Outline")
		(27 "Margin" user)
		(31 "F.CrtYd" user "Package Geometry/Place Bound Top")
		(29 "B.CrtYd" user "Package Geometry/Place Bound Bottom")
		(35 "F.Fab" user "Ref Des/Assembly Top")
		(33 "B.Fab" user "Ref Des/Assembly Bottom")
	)
	(footprint ""
		(layer "F.Cu")
		(at 105.973372 -74.993246 -90)
		(property "Reference" "R3072"
			(at 0 0 270)
			(layer "F.SilkS")
			(hide yes)
			(effects
				(font
					(size 1.27 1.27)
				)
			)
		)
		(property "Value" ""
			(at 0 0 270)
			(layer "F.Fab")
			(effects
				(font
					(size 1.27 1.27)
				)
			)
		)
		(duplicate_pad_numbers_are_jumpers no)
		(fp_line
			(start -0.7874 0.4064)
			(end -0.7874 -0.4064)
			(stroke
				(width 0.1524)
				(type default)
			)
			(layer "F.SilkS")
		)
		(fp_line
			(start 0.7874 0.4064)
			(end -0.7874 0.4064)
			(stroke
				(width 0.1524)
				(type default)
			)
			(layer "F.SilkS")
		)
		(fp_line
			(start -0.7874 -0.4064)
			(end 0.7874 -0.4064)
			(stroke
				(width 0.1524)
				(type default)
			)
			(layer "F.SilkS")
		)
		(fp_line
			(start 0.7874 -0.4064)
			(end 0.7874 0.4064)
			(stroke
				(width 0.1524)
				(type default)
			)
			(layer "F.SilkS")
		)
		(fp_line
			(start -0.67945 0.3048)
			(end -0.67945 -0.305054)
			(stroke
				(width 0.1)
				(type default)
			)
			(layer "F.Fab")
		)
		(fp_line
			(start -0.12065 0.3048)
			(end -0.67945 0.3048)
			(stroke
				(width 0.1)
				(type default)
			)
			(layer "F.Fab")
		)
		(fp_line
			(start 0.120396 0.3048)
			(end 0.120396 0.2794)
			(stroke
				(width 0.1)
				(type default)
			)
			(layer "F.Fab")
		)
		(fp_line
			(start 0.67945 0.3048)
			(end 0.120396 0.3048)
			(stroke
				(width 0.1)
				(type default)
			)
			(layer "F.Fab")
		)
		(fp_line
			(start -0.12065 0.2794)
			(end -0.12065 0.3048)
			(stroke
				(width 0.1)
				(type default)
			)
			(layer "F.Fab")
		)
		(fp_line
			(start 0.120396 0.2794)
			(end -0.12065 0.2794)
			(stroke
				(width 0.1)
				(type default)
			)
			(layer "F.Fab")
		)
		(fp_line
			(start -0.12065 -0.2794)
			(end 0.12065 -0.2794)
			(stroke
				(width 0.1)
				(type default)
			)
			(layer "F.Fab")
		)
		(fp_line
			(start 0.12065 -0.2794)
			(end 0.12065 -0.3048)
			(stroke
				(width 0.1)
				(type default)
			)
			(layer "F.Fab")
		)
		(fp_line
			(start 0.12065 -0.3048)
			(end 0.67945 -0.3048)
			(stroke
				(width 0.1)
				(type default)
			)
			(layer "F.Fab")
		)
		(fp_line
			(start 0.67945 -0.3048)
			(end 0.67945 0.3048)
			(stroke
				(width 0.1)
				(type default)
			)
			(layer "F.Fab")
		)
		(fp_line
			(start -0.67945 -0.305054)
			(end -0.12065 -0.305054)
			(stroke
				(width 0.1)
				(type default)
			)
			(layer "F.Fab")
		)
		(fp_line
			(start -0.12065 -0.305054)
			(end -0.12065 -0.2794)
			(stroke
				(width 0.1)
				(type default)
			)
			(layer "F.Fab")
		)
		(pad "1" smd circle
			(at -0.40005 0 270)
			(size 0 0)
			(layers "F.Cu" "F.Mask" "F.Paste")
			(net "LED_PWRGD_P1V05_PCH_AUX")
		)
		(pad "2" smd circle
			(at 0.40005 0 270)
			(size 0 0)
			(layers "F.Cu" "F.Mask" "F.Paste")
			(net "P3V3_AUX")
		)
	)
	(footprint ""
		(layer "F.Cu")
		(at 460.74457 -36.70808 -90)
		(property "Reference" "R3784"
			(at 0 0 270)
			(layer "F.SilkS")
			(hide yes)
			(effects
				(font
					(size 1.27 1.27)
				)
			)
		)
		(property "Value" ""
			(at 0 0 270)
			(layer "F.Fab")
			(effects
				(font
					(size 1.27 1.27)
				)
			)
		)
		(duplicate_pad_numbers_are_jumpers no)
		(fp_line
			(start -0.7874 0.4064)
			(end -0.7874 -0.4064)
			(stroke
				(width 0.1524)
				(type default)
			)
			(layer "F.SilkS")
		)
		(fp_line
			(start 0.7874 0.4064)
			(end -0.7874 0.4064)
			(stroke
				(width 0.1524)
				(type default)
			)
			(layer "F.SilkS")
		)
		(fp_line
			(start -0.7874 -0.4064)
			(end 0.7874 -0.4064)
			(stroke
				(width 0.1524)
				(type default)
			)
			(layer "F.SilkS")
		)
		(fp_line
			(start 0.7874 -0.4064)
			(end 0.7874 0.4064)
			(stroke
				(width 0.1524)
				(type default)
			)
			(layer "F.SilkS")
		)
		(fp_line
			(start -0.67945 0.3048)
			(end -0.67945 -0.305054)
			(stroke
				(width 0.1)
				(type default)
			)
			(layer "F.Fab")
		)
		(fp_line
			(start -0.12065 0.3048)
			(end -0.67945 0.3048)
			(stroke
				(width 0.1)
				(type default)
			)
			(layer "F.Fab")
		)
		(fp_line
			(start 0.120396 0.3048)
			(end 0.120396 0.2794)
			(stroke
				(width 0.1)
				(type default)
			)
			(layer "F.Fab")
		)
		(fp_line
			(start 0.67945 0.3048)
			(end 0.120396 0.3048)
			(stroke
				(width 0.1)
				(type default)
			)
			(layer "F.Fab")
		)
		(fp_line
			(start -0.12065 0.2794)
			(end -0.12065 0.3048)
			(stroke
				(width 0.1)
				(type default)
			)
			(layer "F.Fab")
		)
		(fp_line
			(start 0.120396 0.2794)
			(end -0.12065 0.2794)
			(stroke
				(width 0.1)
				(type default)
			)
			(layer "F.Fab")
		)
		(fp_line
			(start -0.12065 -0.2794)
			(end 0.12065 -0.2794)
			(stroke
				(width 0.1)
				(type default)
			)
			(layer "F.Fab")
		)
		(fp_line
			(start 0.12065 -0.2794)
			(end 0.12065 -0.3048)
			(stroke
				(width 0.1)
				(type default)
			)
			(layer "F.Fab")
		)
		(fp_line
			(start 0.12065 -0.3048)
			(end 0.67945 -0.3048)
			(stroke
				(width 0.1)
				(type default)
			)
			(layer "F.Fab")
		)
		(fp_line
			(start 0.67945 -0.3048)
			(end 0.67945 0.3048)
			(stroke
				(width 0.1)
				(type default)
			)
			(layer "F.Fab")
		)
		(fp_line
			(start -0.67945 -0.305054)
			(end -0.12065 -0.305054)
			(stroke
				(width 0.1)
				(type default)
			)
			(layer "F.Fab")
		)
		(fp_line
			(start -0.12065 -0.305054)
			(end -0.12065 -0.2794)
			(stroke
				(width 0.1)
				(type default)
			)
			(layer "F.Fab")
		)
		(pad "1" smd circle
			(at -0.40005 0 270)
			(size 0 0)
			(layers "F.Cu" "F.Mask" "F.Paste")
			(net "P12V_OCP_UV_1_R")
		)
		(pad "2" smd circle
			(at 0.40005 0 270)
			(size 0 0)
			(layers "F.Cu" "F.Mask" "F.Paste")
			(net "P12V_OCP_UV_1")
		)
	)
	(footprint ""
		(layer "F.Cu")
		(at 352.270314 -256.654046 -90)
		(property "Reference" "C421"
			(at 0 0 270)
			(layer "F.SilkS")
			(hide yes)
			(effects
				(font
					(size 1.27 1.27)
				)
			)
		)
		(property "Value" ""
			(at 0 0 270)
			(layer "F.Fab")
			(effects
				(font
					(size 1.27 1.27)
				)
			)
		)
		(duplicate_pad_numbers_are_jumpers no)
		(fp_line
			(start -0.7874 0.4064)
			(end -0.7874 -0.4064)
			(stroke
				(width 0.1524)
				(type default)
			)
			(layer "F.SilkS")
		)
		(fp_line
			(start 0.7874 0.4064)
			(end -0.7874 0.4064)
			(stroke
				(width 0.1524)
				(type default)
			)
			(layer "F.SilkS")
		)
		(fp_line
			(start -0.7874 -0.4064)
			(end 0.7874 -0.4064)
			(stroke
				(width 0.1524)
				(type default)
			)
			(layer "F.SilkS")
		)
		(fp_line
			(start 0.7874 -0.4064)
			(end 0.7874 0.4064)
			(stroke
				(width 0.1524)
				(type default)
			)
			(layer "F.SilkS")
		)
		(fp_line
			(start -0.67945 0.3048)
			(end -0.67945 -0.305054)
			(stroke
				(width 0.1)
				(type default)
			)
			(layer "F.Fab")
		)
		(fp_line
			(start -0.12065 0.3048)
			(end -0.67945 0.3048)
			(stroke
				(width 0.1)
				(type default)
			)
			(layer "F.Fab")
		)
		(fp_line
			(start 0.120396 0.3048)
			(end 0.120396 0.2794)
			(stroke
				(width 0.1)
				(type default)
			)
			(layer "F.Fab")
		)
		(fp_line
			(start 0.67945 0.3048)
			(end 0.120396 0.3048)
			(stroke
				(width 0.1)
				(type default)
			)
			(layer "F.Fab")
		)
		(fp_line
			(start -0.12065 0.2794)
			(end -0.12065 0.3048)
			(stroke
				(width 0.1)
				(type default)
			)
			(layer "F.Fab")
		)
		(fp_line
			(start 0.120396 0.2794)
			(end -0.12065 0.2794)
			(stroke
				(width 0.1)
				(type default)
			)
			(layer "F.Fab")
		)
		(fp_line
			(start -0.12065 -0.2794)
			(end 0.12065 -0.2794)
			(stroke
				(width 0.1)
				(type default)
			)
			(layer "F.Fab")
		)
		(fp_line
			(start 0.12065 -0.2794)
			(end 0.12065 -0.3048)
			(stroke
				(width 0.1)
				(type default)
			)
			(layer "F.Fab")
		)
		(fp_line
			(start 0.12065 -0.3048)
			(end 0.67945 -0.3048)
			(stroke
				(width 0.1)
				(type default)
			)
			(layer "F.Fab")
		)
		(fp_line
			(start 0.67945 -0.3048)
			(end 0.67945 0.3048)
			(stroke
				(width 0.1)
				(type default)
			)
			(layer "F.Fab")
		)
		(fp_line
			(start -0.67945 -0.305054)
			(end -0.12065 -0.305054)
			(stroke
				(width 0.1)
				(type default)
			)
			(layer "F.Fab")
		)
		(fp_line
			(start -0.12065 -0.305054)
			(end -0.12065 -0.2794)
			(stroke
				(width 0.1)
				(type default)
			)
			(layer "F.Fab")
		)
		(pad "1" smd circle
			(at -0.40005 0 270)
			(size 0 0)
			(layers "F.Cu" "F.Mask" "F.Paste")
			(net "PVCCFA_EHV_CPU0")
		)
		(pad "2" smd circle
			(at 0.40005 0 270)
			(size 0 0)
			(layers "F.Cu" "F.Mask" "F.Paste")
			(net "GND")
		)
	)
	(footprint ""
		(layer "F.Cu")
		(at 259.064506 -75.923902 -90)
		(property "Reference" "R1389"
			(at 0 0 270)
			(layer "F.SilkS")
			(hide yes)
			(effects
				(font
					(size 1.27 1.27)
				)
			)
		)
		(property "Value" ""
			(at 0 0 270)
			(layer "F.Fab")
			(effects
				(font
					(size 1.27 1.27)
				)
			)
		)
		(duplicate_pad_numbers_are_jumpers no)
		(fp_line
			(start -0.7874 0.4064)
			(end -0.7874 -0.4064)
			(stroke
				(width 0.1524)
				(type default)
			)
			(layer "F.SilkS")
		)
		(fp_line
			(start 0.7874 0.4064)
			(end -0.7874 0.4064)
			(stroke
				(width 0.1524)
				(type default)
			)
			(layer "F.SilkS")
		)
		(fp_line
			(start -0.7874 -0.4064)
			(end 0.7874 -0.4064)
			(stroke
				(width 0.1524)
				(type default)
			)
			(layer "F.SilkS")
		)
		(fp_line
			(start 0.7874 -0.4064)
			(end 0.7874 0.4064)
			(stroke
				(width 0.1524)
				(type default)
			)
			(layer "F.SilkS")
		)
		(fp_line
			(start -0.67945 0.3048)
			(end -0.67945 -0.305054)
			(stroke
				(width 0.1)
				(type default)
			)
			(layer "F.Fab")
		)
		(fp_line
			(start -0.12065 0.3048)
			(end -0.67945 0.3048)
			(stroke
				(width 0.1)
				(type default)
			)
			(layer "F.Fab")
		)
		(fp_line
			(start 0.120396 0.3048)
			(end 0.120396 0.2794)
			(stroke
				(width 0.1)
				(type default)
			)
			(layer "F.Fab")
		)
		(fp_line
			(start 0.67945 0.3048)
			(end 0.120396 0.3048)
			(stroke
				(width 0.1)
				(type default)
			)
			(layer "F.Fab")
		)
		(fp_line
			(start -0.12065 0.2794)
			(end -0.12065 0.3048)
			(stroke
				(width 0.1)
				(type default)
			)
			(layer "F.Fab")
		)
		(fp_line
			(start 0.120396 0.2794)
			(end -0.12065 0.2794)
			(stroke
				(width 0.1)
				(type default)
			)
			(layer "F.Fab")
		)
		(fp_line
			(start -0.12065 -0.2794)
			(end 0.12065 -0.2794)
			(stroke
				(width 0.1)
				(type default)
			)
			(layer "F.Fab")
		)
		(fp_line
			(start 0.12065 -0.2794)
			(end 0.12065 -0.3048)
			(stroke
				(width 0.1)
				(type default)
			)
			(layer "F.Fab")
		)
		(fp_line
			(start 0.12065 -0.3048)
			(end 0.67945 -0.3048)
			(stroke
				(width 0.1)
				(type default)
			)
			(layer "F.Fab")
		)
		(fp_line
			(start 0.67945 -0.3048)
			(end 0.67945 0.3048)
			(stroke
				(width 0.1)
				(type default)
			)
			(layer "F.Fab")
		)
		(fp_line
			(start -0.67945 -0.305054)
			(end -0.12065 -0.305054)
			(stroke
				(width 0.1)
				(type default)
			)
			(layer "F.Fab")
		)
		(fp_line
			(start -0.12065 -0.305054)
			(end -0.12065 -0.2794)
			(stroke
				(width 0.1)
				(type default)
			)
			(layer "F.Fab")
		)
		(pad "1" smd circle
			(at -0.40005 0 270)
			(size 0 0)
			(layers "F.Cu" "F.Mask" "F.Paste")
			(net "FM_P1V05_PCH_AUX_EN")
		)
		(pad "2" smd circle
			(at 0.40005 0 270)
			(size 0 0)
			(layers "F.Cu" "F.Mask" "F.Paste")
			(net "FM_P1V05_PCH_AUX_R_EN")
		)
	)
	(footprint ""
		(layer "F.Cu")
		(at 126.862332 -341.716106 -90)
		(property "Reference" "PC1361"
			(at 0 0 270)
			(layer "F.SilkS")
			(hide yes)
			(effects
				(font
					(size 1.27 1.27)
				)
			)
		)
		(property "Value" ""
			(at 0 0 270)
			(layer "F.Fab")
			(effects
				(font
					(size 1.27 1.27)
				)
			)
		)
		(duplicate_pad_numbers_are_jumpers no)
		(fp_line
			(start -0.7874 0.4064)
			(end -0.7874 -0.4064)
			(stroke
				(width 0.1524)
				(type default)
			)
			(layer "F.SilkS")
		)
		(fp_line
			(start 0.7874 0.4064)
			(end -0.7874 0.4064)
			(stroke
				(width 0.1524)
				(type default)
			)
			(layer "F.SilkS")
		)
		(fp_line
			(start -0.7874 -0.4064)
			(end 0.7874 -0.4064)
			(stroke
				(width 0.1524)
				(type default)
			)
			(layer "F.SilkS")
		)
		(fp_line
			(start 0.7874 -0.4064)
			(end 0.7874 0.4064)
			(stroke
				(width 0.1524)
				(type default)
			)
			(layer "F.SilkS")
		)
		(fp_line
			(start -0.67945 0.3048)
			(end -0.67945 -0.305054)
			(stroke
				(width 0.1)
				(type default)
			)
			(layer "F.Fab")
		)
		(fp_line
			(start -0.12065 0.3048)
			(end -0.67945 0.3048)
			(stroke
				(width 0.1)
				(type default)
			)
			(layer "F.Fab")
		)
		(fp_line
			(start 0.120396 0.3048)
			(end 0.120396 0.2794)
			(stroke
				(width 0.1)
				(type default)
			)
			(layer "F.Fab")
		)
		(fp_line
			(start 0.67945 0.3048)
			(end 0.120396 0.3048)
			(stroke
				(width 0.1)
				(type default)
			)
			(layer "F.Fab")
		)
		(fp_line
			(start -0.12065 0.2794)
			(end -0.12065 0.3048)
			(stroke
				(width 0.1)
				(type default)
			)
			(layer "F.Fab")
		)
		(fp_line
			(start 0.120396 0.2794)
			(end -0.12065 0.2794)
			(stroke
				(width 0.1)
				(type default)
			)
			(layer "F.Fab")
		)
		(fp_line
			(start -0.12065 -0.2794)
			(end 0.12065 -0.2794)
			(stroke
				(width 0.1)
				(type default)
			)
			(layer "F.Fab")
		)
		(fp_line
			(start 0.12065 -0.2794)
			(end 0.12065 -0.3048)
			(stroke
				(width 0.1)
				(type default)
			)
			(layer "F.Fab")
		)
		(fp_line
			(start 0.12065 -0.3048)
			(end 0.67945 -0.3048)
			(stroke
				(width 0.1)
				(type default)
			)
			(layer "F.Fab")
		)
		(fp_line
			(start 0.67945 -0.3048)
			(end 0.67945 0.3048)
			(stroke
				(width 0.1)
				(type default)
			)
			(layer "F.Fab")
		)
		(fp_line
			(start -0.67945 -0.305054)
			(end -0.12065 -0.305054)
			(stroke
				(width 0.1)
				(type default)
			)
			(layer "F.Fab")
		)
		(fp_line
			(start -0.12065 -0.305054)
			(end -0.12065 -0.2794)
			(stroke
				(width 0.1)
				(type default)
			)
			(layer "F.Fab")
		)
		(pad "1" smd circle
			(at -0.40005 0 270)
			(size 0 0)
			(layers "F.Cu" "F.Mask" "F.Paste")
			(net "GND")
		)
		(pad "2" smd circle
			(at 0.40005 0 270)
			(size 0 0)
			(layers "F.Cu" "F.Mask" "F.Paste")
			(net "PVCCIN_CPU1_VREF")
		)
	)
	(footprint ""
		(layer "F.Cu")
		(at 298.16552 -406.6794)
		(property "Reference" "R4685"
			(at 0 0 0)
			(layer "F.SilkS")
			(hide yes)
			(effects
				(font
					(size 1.27 1.27)
				)
			)
		)
		(property "Value" ""
			(at 0 0 0)
			(layer "F.Fab")
			(effects
				(font
					(size 1.27 1.27)
				)
			)
		)
		(duplicate_pad_numbers_are_jumpers no)
		(fp_line
			(start -0.7874 -0.4064)
			(end 0.7874 -0.4064)
			(stroke
				(width 0.1524)
				(type default)
			)
			(layer "F.SilkS")
		)
		(fp_line
			(start -0.7874 0.4064)
			(end -0.7874 -0.4064)
			(stroke
				(width 0.1524)
				(type default)
			)
			(layer "F.SilkS")
		)
		(fp_line
			(start 0.7874 -0.4064)
			(end 0.7874 0.4064)
			(stroke
				(width 0.1524)
				(type default)
			)
			(layer "F.SilkS")
		)
		(fp_line
			(start 0.7874 0.4064)
			(end -0.7874 0.4064)
			(stroke
				(width 0.1524)
				(type default)
			)
			(layer "F.SilkS")
		)
		(fp_line
			(start -0.67945 -0.305054)
			(end -0.12065 -0.305054)
			(stroke
				(width 0.1)
				(type default)
			)
			(layer "F.Fab")
		)
		(fp_line
			(start -0.67945 0.3048)
			(end -0.67945 -0.305054)
			(stroke
				(width 0.1)
				(type default)
			)
			(layer "F.Fab")
		)
		(fp_line
			(start -0.12065 -0.305054)
			(end -0.12065 -0.2794)
			(stroke
				(width 0.1)
				(type default)
			)
			(layer "F.Fab")
		)
		(fp_line
			(start -0.12065 -0.2794)
			(end 0.12065 -0.2794)
			(stroke
				(width 0.1)
				(type default)
			)
			(layer "F.Fab")
		)
		(fp_line
			(start -0.12065 0.2794)
			(end -0.12065 0.3048)
			(stroke
				(width 0.1)
				(type default)
			)
			(layer "F.Fab")
		)
		(fp_line
			(start -0.12065 0.3048)
			(end -0.67945 0.3048)
			(stroke
				(width 0.1)
				(type default)
			)
			(layer "F.Fab")
		)
		(fp_line
			(start 0.120396 0.2794)
			(end -0.12065 0.2794)
			(stroke
				(width 0.1)
				(type default)
			)
			(layer "F.Fab")
		)
		(fp_line
			(start 0.120396 0.3048)
			(end 0.120396 0.2794)
			(stroke
				(width 0.1)
				(type default)
			)
			(layer "F.Fab")
		)
		(fp_line
			(start 0.12065 -0.3048)
			(end 0.67945 -0.3048)
			(stroke
				(width 0.1)
				(type default)
			)
			(layer "F.Fab")
		)
		(fp_line
			(start 0.12065 -0.2794)
			(end 0.12065 -0.3048)
			(stroke
				(width 0.1)
				(type default)
			)
			(layer "F.Fab")
		)
		(fp_line
			(start 0.67945 -0.3048)
			(end 0.67945 0.3048)
			(stroke
				(width 0.1)
				(type default)
			)
			(layer "F.Fab")
		)
		(fp_line
			(start 0.67945 0.3048)
			(end 0.120396 0.3048)
			(stroke
				(width 0.1)
				(type default)
			)
			(layer "F.Fab")
		)
		(pad "1" smd circle
			(at -0.40005 0)
			(size 0 0)
			(layers "F.Cu" "F.Mask" "F.Paste")
			(net "P3V3_AUX")
		)
		(pad "2" smd circle
			(at 0.40005 0)
			(size 0 0)
			(layers "F.Cu" "F.Mask" "F.Paste")
			(net "P12V_HSC_TEMP_ALERT_R_N")
		)
	)
)
